(kicad_pcb
	(version 20260206)
	(generator "pcbnew")
	(generator_version "10.0")
	(general
		(thickness 1.6)
		(legacy_teardrops no)
	)
	(paper "A4")
	(title_block
		(title "panther-plus-userver — 13130-1b_20150205.brd")
		(comment 1 "Honey Badger (Wiwynn) / footprints 477-484 of 1509")
	)
	(layers
		(0 "F.Cu" signal "TOP")
		(4 "In1.Cu" signal "L2")
		(6 "In2.Cu" signal "L3")
		(8 "In3.Cu" signal "L4")
		(10 "In4.Cu" signal "L5")
		(12 "In5.Cu" signal "L6")
		(14 "In6.Cu" signal "L7")
		(16 "In7.Cu" signal "L8")
		(18 "In8.Cu" signal "L9")
		(20 "In9.Cu" signal "L10")
		(22 "In10.Cu" signal "L11")
		(2 "B.Cu" signal "BOTTOM")
		(9 "F.Adhes" user "F.Adhesive")
		(11 "B.Adhes" user "B.Adhesive")
		(13 "F.Paste" user "Package Geometry/Pastemask Top")
		(15 "B.Paste" user "Package Geometry/Pastemask Bottom")
		(5 "F.SilkS" user "Ref Des/Silkscreen Top")
		(7 "B.SilkS" user "Ref Des/Silkscreen Bottom")
		(1 "F.Mask" user "Board Geometry/Soldermask Top")
		(3 "B.Mask" user "Board Geometry/Soldermask Bottom")
		(17 "Dwgs.User" user "User.Drawings")
		(19 "Cmts.User" user "User.Comments")
		(21 "Eco1.User" user "User.Eco1")
		(23 "Eco2.User" user "User.Eco2")
		(25 "Edge.Cuts" user "Board Geometry/Outline")
		(27 "Margin" user)
		(31 "F.CrtYd" user "Package Geometry/Place Bound Top")
		(29 "B.CrtYd" user "Package Geometry/Place Bound Bottom")
		(35 "F.Fab" user "Ref Des/Assembly Top")
		(33 "B.Fab" user "Ref Des/Assembly Bottom")
	)
	(footprint ""
		(layer "F.Cu")
		(at 176.5046 -46.5074)
		(property "Reference" "R179"
			(at 0 0 0)
			(layer "F.SilkS")
			(hide yes)
			(effects
				(font
					(size 1.27 1.27)
				)
			)
		)
		(property "Value" "0R2J-2-GP"
			(at 0.064008 -3.993896 0)
			(unlocked yes)
			(layer "F.Fab")
			(hide yes)
			(effects
				(font
					(size 1.016 1.016)
					(thickness 0.1524)
				)
			)
		)
		(property "Device Type" "R402H16"
			(at 0.064008 -5.517896 0)
			(unlocked yes)
			(layer "F.Fab")
			(hide yes)
			(effects
				(font
					(size 1.016 1.016)
					(thickness 0.1524)
				)
			)
		)
		(duplicate_pad_numbers_are_jumpers no)
		(fp_rect
			(start -0.381 0.8382)
			(end 0.381 -0.8382)
			(stroke
				(width 0)
				(type default)
			)
			(fill no)
			(layer "F.CrtYd")
		)
		(fp_rect
			(start -0.381 0.8382)
			(end 0.381 -0.8382)
			(stroke
				(width 0)
				(type default)
			)
			(fill no)
			(layer "F.Fab")
		)
		(pad "1" smd custom
			(at 0 -0.4318)
			(size 0.127 0.127)
			(layers "F.Cu" "F.Mask" "F.Paste")
			(net "EEPROM_WP")
			(options
				(clearance outline)
				(anchor circle)
			)
			(primitives
				(gr_poly
					(pts
						(arc
							(start -0.2032 -0.2794)
							(mid -0.239121 -0.264521)
							(end -0.254 -0.2286)
						)
						(arc
							(start -0.254 0.2286)
							(mid -0.239121 0.264521)
							(end -0.2032 0.2794)
						)
						(arc
							(start 0.2032 0.2794)
							(mid 0.239121 0.264521)
							(end 0.254 0.2286)
						)
						(arc
							(start 0.254 -0.2286)
							(mid 0.239121 -0.264521)
							(end 0.2032 -0.2794)
						)
					)
					(width 0)
					(fill yes)
				)
			)
		)
		(pad "2" smd custom
			(at 0 0.4318)
			(size 0.127 0.127)
			(layers "F.Cu" "F.Mask" "F.Paste")
			(net "GND")
			(options
				(clearance outline)
				(anchor circle)
			)
			(primitives
				(gr_poly
					(pts
						(arc
							(start -0.2032 -0.2794)
							(mid -0.239121 -0.264521)
							(end -0.254 -0.2286)
						)
						(arc
							(start -0.254 0.2286)
							(mid -0.239121 0.264521)
							(end -0.2032 0.2794)
						)
						(arc
							(start 0.2032 0.2794)
							(mid 0.239121 0.264521)
							(end 0.254 0.2286)
						)
						(arc
							(start 0.254 -0.2286)
							(mid 0.239121 -0.264521)
							(end 0.2032 -0.2794)
						)
					)
					(width 0)
					(fill yes)
				)
			)
		)
	)
	(footprint ""
		(layer "F.Cu")
		(at 56.007 -35.306 -90)
		(property "Reference" "R110"
			(at 0 0 270)
			(layer "F.SilkS")
			(hide yes)
			(effects
				(font
					(size 1.27 1.27)
				)
			)
		)
		(property "Value" "33R2F-3-GP"
			(at 0.064008 -3.993896 270)
			(unlocked yes)
			(layer "F.Fab")
			(hide yes)
			(effects
				(font
					(size 1.016 1.016)
					(thickness 0.1524)
				)
			)
		)
		(property "Device Type" "R402H16"
			(at 0.064008 -5.517896 270)
			(unlocked yes)
			(layer "F.Fab")
			(hide yes)
			(effects
				(font
					(size 1.016 1.016)
					(thickness 0.1524)
				)
			)
		)
		(duplicate_pad_numbers_are_jumpers no)
		(fp_rect
			(start -0.381 0.8382)
			(end 0.381 -0.8382)
			(stroke
				(width 0)
				(type default)
			)
			(fill no)
			(layer "F.CrtYd")
		)
		(fp_rect
			(start -0.381 0.8382)
			(end 0.381 -0.8382)
			(stroke
				(width 0)
				(type default)
			)
			(fill no)
			(layer "F.Fab")
		)
		(pad "1" smd custom
			(at 0 -0.4318 270)
			(size 0.127 0.127)
			(layers "F.Cu" "F.Mask" "F.Paste")
			(net "SPI_CPU_WP#")
			(options
				(clearance outline)
				(anchor circle)
			)
			(primitives
				(gr_poly
					(pts
						(arc
							(start -0.2032 -0.2794)
							(mid -0.239121 -0.264521)
							(end -0.254 -0.2286)
						)
						(arc
							(start -0.254 0.2286)
							(mid -0.239121 0.264521)
							(end -0.2032 0.2794)
						)
						(arc
							(start 0.2032 0.2794)
							(mid 0.239121 0.264521)
							(end 0.254 0.2286)
						)
						(arc
							(start 0.254 -0.2286)
							(mid 0.239121 -0.264521)
							(end 0.2032 -0.2794)
						)
					)
					(width 0)
					(fill yes)
				)
			)
		)
		(pad "2" smd custom
			(at 0 0.4318 270)
			(size 0.127 0.127)
			(layers "F.Cu" "F.Mask" "F.Paste")
			(net "SPI_WP_R_N_1")
			(options
				(clearance outline)
				(anchor circle)
			)
			(primitives
				(gr_poly
					(pts
						(arc
							(start -0.2032 -0.2794)
							(mid -0.239121 -0.264521)
							(end -0.254 -0.2286)
						)
						(arc
							(start -0.254 0.2286)
							(mid -0.239121 0.264521)
							(end -0.2032 0.2794)
						)
						(arc
							(start 0.2032 0.2794)
							(mid 0.239121 0.264521)
							(end 0.254 0.2286)
						)
						(arc
							(start 0.254 -0.2286)
							(mid 0.239121 -0.264521)
							(end 0.2032 -0.2794)
						)
					)
					(width 0)
					(fill yes)
				)
			)
		)
	)
	(footprint ""
		(layer "F.Cu")
		(at 198.755 -11.049 180)
		(property "Reference" "R339"
			(at 0 0 180)
			(layer "F.SilkS")
			(hide yes)
			(effects
				(font
					(size 1.27 1.27)
				)
			)
		)
		(property "Value" "1KR2F-3-GP"
			(at 1.7907 -1.1176 180)
			(unlocked yes)
			(layer "F.Fab")
			(hide yes)
			(effects
				(font
					(size 1.016 1.016)
					(thickness 0.1524)
				)
			)
		)
		(property "Device Type" "R402H16"
			(at 1.7907 -2.6416 180)
			(unlocked yes)
			(layer "F.Fab")
			(hide yes)
			(effects
				(font
					(size 1.016 1.016)
					(thickness 0.1524)
				)
			)
		)
		(duplicate_pad_numbers_are_jumpers no)
		(fp_rect
			(start -0.381 0.8382)
			(end 0.381 -0.8382)
			(stroke
				(width 0)
				(type default)
			)
			(fill no)
			(layer "F.CrtYd")
		)
		(fp_rect
			(start -0.381 0.8382)
			(end 0.381 -0.8382)
			(stroke
				(width 0)
				(type default)
			)
			(fill no)
			(layer "F.Fab")
		)
		(pad "1" smd custom
			(at 0 -0.4318 180)
			(size 0.127 0.127)
			(layers "F.Cu" "F.Mask" "F.Paste")
			(net "JTAG_CPU_PLD_TDO")
			(options
				(clearance outline)
				(anchor circle)
			)
			(primitives
				(gr_poly
					(pts
						(arc
							(start -0.2032 -0.2794)
							(mid -0.239121 -0.264521)
							(end -0.254 -0.2286)
						)
						(arc
							(start -0.254 0.2286)
							(mid -0.239121 0.264521)
							(end -0.2032 0.2794)
						)
						(arc
							(start 0.2032 0.2794)
							(mid 0.239121 0.264521)
							(end 0.254 0.2286)
						)
						(arc
							(start 0.254 -0.2286)
							(mid 0.239121 -0.264521)
							(end 0.2032 -0.2794)
						)
					)
					(width 0)
					(fill yes)
				)
			)
		)
		(pad "2" smd custom
			(at 0 0.4318 180)
			(size 0.127 0.127)
			(layers "F.Cu" "F.Mask" "F.Paste")
			(net "GND")
			(options
				(clearance outline)
				(anchor circle)
			)
			(primitives
				(gr_poly
					(pts
						(arc
							(start -0.2032 -0.2794)
							(mid -0.239121 -0.264521)
							(end -0.254 -0.2286)
						)
						(arc
							(start -0.254 0.2286)
							(mid -0.239121 0.264521)
							(end -0.2032 0.2794)
						)
						(arc
							(start 0.2032 0.2794)
							(mid 0.239121 0.264521)
							(end 0.254 0.2286)
						)
						(arc
							(start 0.254 -0.2286)
							(mid 0.239121 -0.264521)
							(end 0.2032 -0.2794)
						)
					)
					(width 0)
					(fill yes)
				)
			)
		)
	)
	(footprint ""
		(layer "F.Cu")
		(at 8.509 -64.516 90)
		(property "Reference" "C184"
			(at 0 0 90)
			(layer "F.SilkS")
			(hide yes)
			(effects
				(font
					(size 1.27 1.27)
				)
			)
		)
		(property "Value" "SCD1U16V2KX-3GP"
			(at 1.1811 -2.7051 90)
			(unlocked yes)
			(layer "F.Fab")
			(hide yes)
			(effects
				(font
					(size 1.016 1.016)
					(thickness 0.1524)
				)
			)
		)
		(property "Device Type" "C402H22"
			(at 1.1811 -4.2291 90)
			(unlocked yes)
			(layer "F.Fab")
			(hide yes)
			(effects
				(font
					(size 1.016 1.016)
					(thickness 0.1524)
				)
			)
		)
		(duplicate_pad_numbers_are_jumpers no)
		(fp_rect
			(start -0.381 0.7366)
			(end 0.381 -0.7366)
			(stroke
				(width 0)
				(type default)
			)
			(fill no)
			(layer "F.CrtYd")
		)
		(fp_rect
			(start -0.381 0.7366)
			(end 0.381 -0.7366)
			(stroke
				(width 0)
				(type default)
			)
			(fill no)
			(layer "F.Fab")
		)
		(pad "1" smd custom
			(at 0 -0.4572 90)
			(size 0.1143 0.1143)
			(layers "F.Cu" "F.Mask" "F.Paste")
			(net "P2E_CPU_NGFF_C_RX_DP15")
			(options
				(clearance outline)
				(anchor circle)
			)
			(primitives
				(gr_poly
					(pts
						(arc
							(start -0.254 -0.1778)
							(mid -0.239121 -0.213721)
							(end -0.2032 -0.2286)
						)
						(arc
							(start 0.2032 -0.2286)
							(mid 0.239121 -0.213721)
							(end 0.254 -0.1778)
						)
						(arc
							(start 0.254 0.1778)
							(mid 0.239121 0.213721)
							(end 0.2032 0.2286)
						)
						(arc
							(start -0.2032 0.2286)
							(mid -0.239121 0.213721)
							(end -0.254 0.1778)
						)
					)
					(width 0)
					(fill yes)
				)
			)
		)
		(pad "2" smd custom
			(at 0 0.4572 90)
			(size 0.1143 0.1143)
			(layers "F.Cu" "F.Mask" "F.Paste")
			(net "P2E_CPU_NGFF_RX_DP15")
			(options
				(clearance outline)
				(anchor circle)
			)
			(primitives
				(gr_poly
					(pts
						(arc
							(start -0.254 -0.1778)
							(mid -0.239121 -0.213721)
							(end -0.2032 -0.2286)
						)
						(arc
							(start 0.2032 -0.2286)
							(mid 0.239121 -0.213721)
							(end 0.254 -0.1778)
						)
						(arc
							(start 0.254 0.1778)
							(mid 0.239121 0.213721)
							(end 0.2032 0.2286)
						)
						(arc
							(start -0.2032 0.2286)
							(mid -0.239121 0.213721)
							(end -0.254 0.1778)
						)
					)
					(width 0)
					(fill yes)
				)
			)
		)
	)
	(footprint ""
		(layer "F.Cu")
		(at 50.1904 -22.987 180)
		(property "Reference" "R441"
			(at 0 0 180)
			(layer "F.SilkS")
			(hide yes)
			(effects
				(font
					(size 1.27 1.27)
				)
			)
		)
		(property "Value" "4K7R2F-GP"
			(at 1.7907 -1.1176 180)
			(unlocked yes)
			(layer "F.Fab")
			(hide yes)
			(effects
				(font
					(size 1.016 1.016)
					(thickness 0.1524)
				)
			)
		)
		(property "Device Type" "R402H16"
			(at 1.7907 -2.6416 180)
			(unlocked yes)
			(layer "F.Fab")
			(hide yes)
			(effects
				(font
					(size 1.016 1.016)
					(thickness 0.1524)
				)
			)
		)
		(duplicate_pad_numbers_are_jumpers no)
		(fp_rect
			(start -0.381 0.8382)
			(end 0.381 -0.8382)
			(stroke
				(width 0)
				(type default)
			)
			(fill no)
			(layer "F.CrtYd")
		)
		(fp_rect
			(start -0.381 0.8382)
			(end 0.381 -0.8382)
			(stroke
				(width 0)
				(type default)
			)
			(fill no)
			(layer "F.Fab")
		)
		(pad "1" smd custom
			(at 0 -0.4318 180)
			(size 0.127 0.127)
			(layers "F.Cu" "F.Mask" "F.Paste")
			(net "P3V3")
			(options
				(clearance outline)
				(anchor circle)
			)
			(primitives
				(gr_poly
					(pts
						(arc
							(start -0.2032 -0.2794)
							(mid -0.239121 -0.264521)
							(end -0.254 -0.2286)
						)
						(arc
							(start -0.254 0.2286)
							(mid -0.239121 0.264521)
							(end -0.2032 0.2794)
						)
						(arc
							(start 0.2032 0.2794)
							(mid 0.239121 0.264521)
							(end 0.254 0.2286)
						)
						(arc
							(start 0.254 -0.2286)
							(mid 0.239121 -0.264521)
							(end 0.2032 -0.2794)
						)
					)
					(width 0)
					(fill yes)
				)
			)
		)
		(pad "2" smd custom
			(at 0 0.4318 180)
			(size 0.127 0.127)
			(layers "F.Cu" "F.Mask" "F.Paste")
			(net "CLKBUFF_OE7#")
			(options
				(clearance outline)
				(anchor circle)
			)
			(primitives
				(gr_poly
					(pts
						(arc
							(start -0.2032 -0.2794)
							(mid -0.239121 -0.264521)
							(end -0.254 -0.2286)
						)
						(arc
							(start -0.254 0.2286)
							(mid -0.239121 0.264521)
							(end -0.2032 0.2794)
						)
						(arc
							(start 0.2032 0.2794)
							(mid 0.239121 0.264521)
							(end 0.254 0.2286)
						)
						(arc
							(start 0.254 -0.2286)
							(mid 0.239121 -0.264521)
							(end 0.2032 -0.2794)
						)
					)
					(width 0)
					(fill yes)
				)
			)
		)
	)
	(footprint ""
		(layer "F.Cu")
		(at 44.958 -34.925)
		(property "Reference" "R245"
			(at 0 0 0)
			(layer "F.SilkS")
			(hide yes)
			(effects
				(font
					(size 1.27 1.27)
				)
			)
		)
		(property "Value" "100R3F-1-GP"
			(at -0.0254 -2.5146 0)
			(unlocked yes)
			(layer "F.Fab")
			(hide yes)
			(effects
				(font
					(size 1.016 1.016)
					(thickness 0.1524)
				)
			)
		)
		(property "Device Type" "R603H22"
			(at -0.0254 -4.0386 0)
			(unlocked yes)
			(layer "F.Fab")
			(hide yes)
			(effects
				(font
					(size 1.016 1.016)
					(thickness 0.1524)
				)
			)
		)
		(duplicate_pad_numbers_are_jumpers no)
		(fp_line
			(start -0.2032 0)
			(end -0.4191 0)
			(stroke
				(width 0.2032)
				(type default)
			)
			(layer "F.SilkS")
		)
		(fp_line
			(start 0.4318 0)
			(end 0.2032 0)
			(stroke
				(width 0.2032)
				(type default)
			)
			(layer "F.SilkS")
		)
		(fp_rect
			(start -0.635 1.1811)
			(end 0.635 -1.1811)
			(stroke
				(width 0)
				(type default)
			)
			(fill no)
			(layer "F.CrtYd")
		)
		(fp_rect
			(start -0.635 1.1811)
			(end 0.635 -1.1811)
			(stroke
				(width 0)
				(type default)
			)
			(fill no)
			(layer "F.Fab")
		)
		(pad "1" smd custom
			(at 0 -0.6604)
			(size 0.19685 0.19685)
			(layers "F.Cu" "F.Mask" "F.Paste")
			(net "XDP_PWRBTN#")
			(options
				(clearance outline)
				(anchor circle)
			)
			(primitives
				(gr_poly
					(pts
						(arc
							(start 0.508 -0.2921)
							(mid 0.478242 -0.363942)
							(end 0.4064 -0.3937)
						)
						(arc
							(start -0.4064 -0.3937)
							(mid -0.478242 -0.363942)
							(end -0.508 -0.2921)
						)
						(arc
							(start -0.508 0.2921)
							(mid -0.478242 0.363942)
							(end -0.4064 0.3937)
						)
						(arc
							(start 0.4064 0.3937)
							(mid 0.478242 0.363942)
							(end 0.508 0.2921)
						)
					)
					(width 0)
					(fill yes)
				)
			)
		)
		(pad "2" smd custom
			(at 0 0.6604)
			(size 0.19685 0.19685)
			(layers "F.Cu" "F.Mask" "F.Paste")
			(net "XDP_PWRBTN_R#")
			(options
				(clearance outline)
				(anchor circle)
			)
			(primitives
				(gr_poly
					(pts
						(arc
							(start 0.508 -0.2921)
							(mid 0.478242 -0.363942)
							(end 0.4064 -0.3937)
						)
						(arc
							(start -0.4064 -0.3937)
							(mid -0.478242 -0.363942)
							(end -0.508 -0.2921)
						)
						(arc
							(start -0.508 0.2921)
							(mid -0.478242 0.363942)
							(end -0.4064 0.3937)
						)
						(arc
							(start 0.4064 0.3937)
							(mid 0.478242 0.363942)
							(end 0.508 0.2921)
						)
					)
					(width 0)
					(fill yes)
				)
			)
		)
	)
	(footprint ""
		(layer "F.Cu")
		(at 24.638 -66.9036)
		(property "Reference" "PR24"
			(at 0 0 0)
			(layer "F.SilkS")
			(hide yes)
			(effects
				(font
					(size 1.27 1.27)
				)
			)
		)
		(property "Value" "10KR2F-2-GP"
			(at 1.7907 -1.1176 0)
			(unlocked yes)
			(layer "F.Fab")
			(hide yes)
			(effects
				(font
					(size 1.016 1.016)
					(thickness 0.1524)
				)
			)
		)
		(property "Device Type" "R402H16"
			(at 1.7907 -2.6416 0)
			(unlocked yes)
			(layer "F.Fab")
			(hide yes)
			(effects
				(font
					(size 1.016 1.016)
					(thickness 0.1524)
				)
			)
		)
		(duplicate_pad_numbers_are_jumpers no)
		(fp_rect
			(start -0.381 0.8382)
			(end 0.381 -0.8382)
			(stroke
				(width 0)
				(type default)
			)
			(fill no)
			(layer "F.CrtYd")
		)
		(fp_rect
			(start -0.381 0.8382)
			(end 0.381 -0.8382)
			(stroke
				(width 0)
				(type default)
			)
			(fill no)
			(layer "F.Fab")
		)
		(pad "1" smd custom
			(at 0 -0.4318)
			(size 0.127 0.127)
			(layers "F.Cu" "F.Mask" "F.Paste")
			(net "VR_PVNN_PHASE")
			(options
				(clearance outline)
				(anchor circle)
			)
			(primitives
				(gr_poly
					(pts
						(arc
							(start -0.2032 -0.2794)
							(mid -0.239121 -0.264521)
							(end -0.254 -0.2286)
						)
						(arc
							(start -0.254 0.2286)
							(mid -0.239121 0.264521)
							(end -0.2032 0.2794)
						)
						(arc
							(start 0.2032 0.2794)
							(mid 0.239121 0.264521)
							(end 0.254 0.2286)
						)
						(arc
							(start 0.254 -0.2286)
							(mid 0.239121 -0.264521)
							(end 0.2032 -0.2794)
						)
					)
					(width 0)
					(fill yes)
				)
			)
		)
		(pad "2" smd custom
			(at 0 0.4318)
			(size 0.127 0.127)
			(layers "F.Cu" "F.Mask" "F.Paste")
			(net "VR_PVNN_GH_R")
			(options
				(clearance outline)
				(anchor circle)
			)
			(primitives
				(gr_poly
					(pts
						(arc
							(start -0.2032 -0.2794)
							(mid -0.239121 -0.264521)
							(end -0.254 -0.2286)
						)
						(arc
							(start -0.254 0.2286)
							(mid -0.239121 0.264521)
							(end -0.2032 0.2794)
						)
						(arc
							(start 0.2032 0.2794)
							(mid 0.239121 0.264521)
							(end 0.254 0.2286)
						)
						(arc
							(start 0.254 -0.2286)
							(mid 0.239121 -0.264521)
							(end 0.2032 -0.2794)
						)
					)
					(width 0)
					(fill yes)
				)
			)
		)
	)
	(footprint ""
		(layer "F.Cu")
		(at 93.472 -13.208)
		(property "Reference" "R444"
			(at 0 0 0)
			(layer "F.SilkS")
			(hide yes)
			(effects
				(font
					(size 1.27 1.27)
				)
			)
		)
		(property "Value" "4K7R2F-GP"
			(at 1.7907 -1.1176 0)
			(unlocked yes)
			(layer "F.Fab")
			(hide yes)
			(effects
				(font
					(size 1.016 1.016)
					(thickness 0.1524)
				)
			)
		)
		(property "Device Type" "R402H16"
			(at 1.7907 -2.6416 0)
			(unlocked yes)
			(layer "F.Fab")
			(hide yes)
			(effects
				(font
					(size 1.016 1.016)
					(thickness 0.1524)
				)
			)
		)
		(duplicate_pad_numbers_are_jumpers no)
		(fp_rect
			(start -0.381 0.8382)
			(end 0.381 -0.8382)
			(stroke
				(width 0)
				(type default)
			)
			(fill no)
			(layer "F.CrtYd")
		)
		(fp_rect
			(start -0.381 0.8382)
			(end 0.381 -0.8382)
			(stroke
				(width 0)
				(type default)
			)
			(fill no)
			(layer "F.Fab")
		)
		(pad "1" smd custom
			(at 0 -0.4318)
			(size 0.127 0.127)
			(layers "F.Cu" "F.Mask" "F.Paste")
			(net "P3V3_STBY")
			(options
				(clearance outline)
				(anchor circle)
			)
			(primitives
				(gr_poly
					(pts
						(arc
							(start -0.2032 -0.2794)
							(mid -0.239121 -0.264521)
							(end -0.254 -0.2286)
						)
						(arc
							(start -0.254 0.2286)
							(mid -0.239121 0.264521)
							(end -0.2032 0.2794)
						)
						(arc
							(start 0.2032 0.2794)
							(mid 0.239121 0.264521)
							(end 0.254 0.2286)
						)
						(arc
							(start 0.254 -0.2286)
							(mid 0.239121 -0.264521)
							(end 0.2032 -0.2794)
						)
					)
					(width 0)
					(fill yes)
				)
			)
		)
		(pad "2" smd custom
			(at 0 0.4318)
			(size 0.127 0.127)
			(layers "F.Cu" "F.Mask" "F.Paste")
			(net "SLOT_ID0")
			(options
				(clearance outline)
				(anchor circle)
			)
			(primitives
				(gr_poly
					(pts
						(arc
							(start -0.2032 -0.2794)
							(mid -0.239121 -0.264521)
							(end -0.254 -0.2286)
						)
						(arc
							(start -0.254 0.2286)
							(mid -0.239121 0.264521)
							(end -0.2032 0.2794)
						)
						(arc
							(start 0.2032 0.2794)
							(mid 0.239121 0.264521)
							(end 0.254 0.2286)
						)
						(arc
							(start 0.254 -0.2286)
							(mid 0.239121 -0.264521)
							(end 0.2032 -0.2794)
						)
					)
					(width 0)
					(fill yes)
				)
			)
		)
	)
)
